# SCM (Grand Teton) — schematic netlist excerpt (pin names and nets, part order shuffled) for the footprints in the layout excerpt that follows; sources: Cadence DE-HDL packaged netlist, KiCad conversion of 12092022_DA0F0TMDCD0_F0T_Management_Board_D_brd_V3_OCP.brd

PC259  Q_CAP  22UF 4V 20% X6S  pkg 0805  page 55 : A = P1V2_AUX ; B = GND
R408  Q_RES  4.7K 1% EMPTY  pkg 0402LF  page 46 : A = P3V3_AUX ; B = SPI_BMC_TPM_CLK
C153  Q_CAP  0.001UF 50V 10% EMPTY  pkg C0402  page 53 : A = PWRGD_P2V5_AUX_R ; B = GND

(kicad_pcb
	(version 20260206)
	(generator "pcbnew")
	(generator_version "10.0")
	(general
		(thickness 1.6)
		(legacy_teardrops no)
	)
	(paper "A4")
	(title_block
		(title "12092022_DA0F0TMDCD0_F0T_Management_Board_D_brd_V3_OCP.brd")
		(comment 1 "Grand Teton / footprints 720-722 of 1440")
	)
	(layers
		(0 "F.Cu" signal "TOP")
		(4 "In1.Cu" signal "GND")
		(6 "In2.Cu" signal "IN1")
		(8 "In3.Cu" signal "GND1")
		(10 "In4.Cu" signal "IN2")
		(12 "In5.Cu" signal "VCC")
		(14 "In6.Cu" signal "VCC1")
		(16 "In7.Cu" signal "IN3")
		(18 "In8.Cu" signal "GND2")
		(20 "In9.Cu" signal "IN4")
		(22 "In10.Cu" signal "GND3")
		(2 "B.Cu" signal "BOTTOM")
		(9 "F.Adhes" user "F.Adhesive")
		(11 "B.Adhes" user "B.Adhesive")
		(13 "F.Paste" user "Package Geometry/Pastemask Top")
		(15 "B.Paste" user "Package Geometry/Pastemask Bottom")
		(5 "F.SilkS" user "Ref Des/Silkscreen Top")
		(7 "B.SilkS" user "Ref Des/Silkscreen Bottom")
		(1 "F.Mask" user "Board Geometry/Soldermask Top")
		(3 "B.Mask" user "Board Geometry/Soldermask Bottom")
		(17 "Dwgs.User" user "User.Drawings")
		(19 "Cmts.User" user "User.Comments")
		(21 "Eco1.User" user "User.Eco1")
		(23 "Eco2.User" user "User.Eco2")
		(25 "Edge.Cuts" user "Board Geometry/Outline")
		(27 "Margin" user)
		(31 "F.CrtYd" user "Package Geometry/Place Bound Top")
		(29 "B.CrtYd" user "Package Geometry/Place Bound Bottom")
		(35 "F.Fab" user "Ref Des/Assembly Top")
		(33 "B.Fab" user "Ref Des/Assembly Bottom")
	)
	(footprint ""
		(layer "F.Cu")
		(at 77.55128 -59.065922 -90)
		(property "Reference" "PC259"
			(at 0 0 270)
			(layer "F.SilkS")
			(hide yes)
			(effects
				(font
					(size 1.27 1.27)
				)
			)
		)
		(property "Value" ""
			(at 0 0 270)
			(layer "F.Fab")
			(effects
				(font
					(size 1.27 1.27)
				)
			)
		)
		(duplicate_pad_numbers_are_jumpers no)
		(fp_line
			(start -1.651 0.8382)
			(end -1.651 -0.8382)
			(stroke
				(width 0.1524)
				(type default)
			)
			(layer "F.SilkS")
		)
		(fp_line
			(start 0 0.8382)
			(end 0 -0.8382)
			(stroke
				(width 0.1524)
				(type default)
			)
			(layer "F.SilkS")
		)
		(fp_line
			(start 1.651 0.8382)
			(end -1.651 0.8382)
			(stroke
				(width 0.1524)
				(type default)
			)
			(layer "F.SilkS")
		)
		(fp_line
			(start -1.651 -0.8382)
			(end 1.651 -0.8382)
			(stroke
				(width 0.1524)
				(type default)
			)
			(layer "F.SilkS")
		)
		(fp_line
			(start 1.651 -0.8382)
			(end 1.651 0.8382)
			(stroke
				(width 0.1524)
				(type default)
			)
			(layer "F.SilkS")
		)
		(fp_line
			(start -1.55956 0.7366)
			(end -1.524 0.7366)
			(stroke
				(width 0.1)
				(type default)
			)
			(layer "F.Fab")
		)
		(fp_line
			(start -1.524 0.7366)
			(end 1.524 0.7366)
			(stroke
				(width 0.1)
				(type default)
			)
			(layer "F.Fab")
		)
		(fp_line
			(start 1.524 0.7366)
			(end 1.55956 0.7366)
			(stroke
				(width 0.1)
				(type default)
			)
			(layer "F.Fab")
		)
		(fp_line
			(start 1.55956 0.7366)
			(end 1.55956 -0.7366)
			(stroke
				(width 0.1)
				(type default)
			)
			(layer "F.Fab")
		)
		(fp_line
			(start -1.55956 -0.7366)
			(end -1.55956 0.7366)
			(stroke
				(width 0.1)
				(type default)
			)
			(layer "F.Fab")
		)
		(fp_line
			(start -1.524 -0.7366)
			(end -1.55956 -0.7366)
			(stroke
				(width 0.1)
				(type default)
			)
			(layer "F.Fab")
		)
		(fp_line
			(start 1.524 -0.7366)
			(end -1.524 -0.7366)
			(stroke
				(width 0.1)
				(type default)
			)
			(layer "F.Fab")
		)
		(fp_line
			(start 1.55956 -0.7366)
			(end 1.524 -0.7366)
			(stroke
				(width 0.1)
				(type default)
			)
			(layer "F.Fab")
		)
		(pad "1" smd rect
			(at -0.94996 0 90)
			(size 1.1176 1.3716)
			(layers "F.Cu" "F.Mask" "F.Paste")
			(net "P1V2_AUX")
		)
		(pad "2" smd rect
			(at 0.94996 0 90)
			(size 1.1176 1.3716)
			(layers "F.Cu" "F.Mask" "F.Paste")
			(net "GND")
		)
	)
	(footprint ""
		(layer "F.Cu")
		(at 81.788 -37.211 90)
		(property "Reference" "C153"
			(at 0 0 90)
			(layer "F.SilkS")
			(hide yes)
			(effects
				(font
					(size 1.27 1.27)
				)
			)
		)
		(property "Value" ""
			(at 0 0 90)
			(layer "F.Fab")
			(effects
				(font
					(size 1.27 1.27)
				)
			)
		)
		(duplicate_pad_numbers_are_jumpers no)
		(fp_line
			(start 0.7874 -0.4064)
			(end 0.7874 0.4064)
			(stroke
				(width 0.1524)
				(type default)
			)
			(layer "F.SilkS")
		)
		(fp_line
			(start -0.7874 -0.4064)
			(end 0.7874 -0.4064)
			(stroke
				(width 0.1524)
				(type default)
			)
			(layer "F.SilkS")
		)
		(fp_line
			(start 0.7874 0.4064)
			(end -0.7874 0.4064)
			(stroke
				(width 0.1524)
				(type default)
			)
			(layer "F.SilkS")
		)
		(fp_line
			(start -0.7874 0.4064)
			(end -0.7874 -0.4064)
			(stroke
				(width 0.1524)
				(type default)
			)
			(layer "F.SilkS")
		)
		(fp_line
			(start -0.12065 -0.305054)
			(end -0.12065 -0.2794)
			(stroke
				(width 0.1)
				(type default)
			)
			(layer "F.Fab")
		)
		(fp_line
			(start -0.67945 -0.305054)
			(end -0.12065 -0.305054)
			(stroke
				(width 0.1)
				(type default)
			)
			(layer "F.Fab")
		)
		(fp_line
			(start 0.67945 -0.3048)
			(end 0.67945 0.3048)
			(stroke
				(width 0.1)
				(type default)
			)
			(layer "F.Fab")
		)
		(fp_line
			(start 0.12065 -0.3048)
			(end 0.67945 -0.3048)
			(stroke
				(width 0.1)
				(type default)
			)
			(layer "F.Fab")
		)
		(fp_line
			(start 0.12065 -0.2794)
			(end 0.12065 -0.3048)
			(stroke
				(width 0.1)
				(type default)
			)
			(layer "F.Fab")
		)
		(fp_line
			(start -0.12065 -0.2794)
			(end 0.12065 -0.2794)
			(stroke
				(width 0.1)
				(type default)
			)
			(layer "F.Fab")
		)
		(fp_line
			(start 0.120396 0.2794)
			(end -0.12065 0.2794)
			(stroke
				(width 0.1)
				(type default)
			)
			(layer "F.Fab")
		)
		(fp_line
			(start -0.12065 0.2794)
			(end -0.12065 0.3048)
			(stroke
				(width 0.1)
				(type default)
			)
			(layer "F.Fab")
		)
		(fp_line
			(start 0.67945 0.3048)
			(end 0.120396 0.3048)
			(stroke
				(width 0.1)
				(type default)
			)
			(layer "F.Fab")
		)
		(fp_line
			(start 0.120396 0.3048)
			(end 0.120396 0.2794)
			(stroke
				(width 0.1)
				(type default)
			)
			(layer "F.Fab")
		)
		(fp_line
			(start -0.12065 0.3048)
			(end -0.67945 0.3048)
			(stroke
				(width 0.1)
				(type default)
			)
			(layer "F.Fab")
		)
		(fp_line
			(start -0.67945 0.3048)
			(end -0.67945 -0.305054)
			(stroke
				(width 0.1)
				(type default)
			)
			(layer "F.Fab")
		)
		(pad "1" smd circle
			(at -0.40005 0 90)
			(size 0 0)
			(layers "F.Cu" "F.Mask" "F.Paste")
			(net "PWRGD_P2V5_AUX_R")
		)
		(pad "2" smd circle
			(at 0.40005 0 90)
			(size 0 0)
			(layers "F.Cu" "F.Mask" "F.Paste")
			(net "GND")
		)
	)
	(footprint ""
		(layer "F.Cu")
		(at 84.201 -91.059)
		(property "Reference" "R408"
			(at 0 0 0)
			(layer "F.SilkS")
			(hide yes)
			(effects
				(font
					(size 1.27 1.27)
				)
			)
		)
		(property "Value" ""
			(at 0 0 0)
			(layer "F.Fab")
			(effects
				(font
					(size 1.27 1.27)
				)
			)
		)
		(duplicate_pad_numbers_are_jumpers no)
		(fp_line
			(start -0.7874 -0.4064)
			(end 0.7874 -0.4064)
			(stroke
				(width 0.1524)
				(type default)
			)
			(layer "F.SilkS")
		)
		(fp_line
			(start -0.7874 0.4064)
			(end -0.7874 -0.4064)
			(stroke
				(width 0.1524)
				(type default)
			)
			(layer "F.SilkS")
		)
		(fp_line
			(start 0.7874 -0.4064)
			(end 0.7874 0.4064)
			(stroke
				(width 0.1524)
				(type default)
			)
			(layer "F.SilkS")
		)
		(fp_line
			(start 0.7874 0.4064)
			(end -0.7874 0.4064)
			(stroke
				(width 0.1524)
				(type default)
			)
			(layer "F.SilkS")
		)
		(fp_line
			(start -0.67945 -0.305054)
			(end -0.12065 -0.305054)
			(stroke
				(width 0.1)
				(type default)
			)
			(layer "F.Fab")
		)
		(fp_line
			(start -0.67945 0.3048)
			(end -0.67945 -0.305054)
			(stroke
				(width 0.1)
				(type default)
			)
			(layer "F.Fab")
		)
		(fp_line
			(start -0.12065 -0.305054)
			(end -0.12065 -0.2794)
			(stroke
				(width 0.1)
				(type default)
			)
			(layer "F.Fab")
		)
		(fp_line
			(start -0.12065 -0.2794)
			(end 0.12065 -0.2794)
			(stroke
				(width 0.1)
				(type default)
			)
			(layer "F.Fab")
		)
		(fp_line
			(start -0.12065 0.2794)
			(end -0.12065 0.3048)
			(stroke
				(width 0.1)
				(type default)
			)
			(layer "F.Fab")
		)
		(fp_line
			(start -0.12065 0.3048)
			(end -0.67945 0.3048)
			(stroke
				(width 0.1)
				(type default)
			)
			(layer "F.Fab")
		)
		(fp_line
			(start 0.120396 0.2794)
			(end -0.12065 0.2794)
			(stroke
				(width 0.1)
				(type default)
			)
			(layer "F.Fab")
		)
		(fp_line
			(start 0.120396 0.3048)
			(end 0.120396 0.2794)
			(stroke
				(width 0.1)
				(type default)
			)
			(layer "F.Fab")
		)
		(fp_line
			(start 0.12065 -0.3048)
			(end 0.67945 -0.3048)
			(stroke
				(width 0.1)
				(type default)
			)
			(layer "F.Fab")
		)
		(fp_line
			(start 0.12065 -0.2794)
			(end 0.12065 -0.3048)
			(stroke
				(width 0.1)
				(type default)
			)
			(layer "F.Fab")
		)
		(fp_line
			(start 0.67945 -0.3048)
			(end 0.67945 0.3048)
			(stroke
				(width 0.1)
				(type default)
			)
			(layer "F.Fab")
		)
		(fp_line
			(start 0.67945 0.3048)
			(end 0.120396 0.3048)
			(stroke
				(width 0.1)
				(type default)
			)
			(layer "F.Fab")
		)
		(pad "1" smd circle
			(at -0.40005 0)
			(size 0 0)
			(layers "F.Cu" "F.Mask" "F.Paste")
			(net "P3V3_AUX")
		)
		(pad "2" smd circle
			(at 0.40005 0)
			(size 0 0)
			(layers "F.Cu" "F.Mask" "F.Paste")
			(net "SPI_BMC_TPM_CLK")
		)
	)
)
